FILE_TYPE = MACRO_DRAWING;
SET COLOR_WIRE YELLOW;
SET COLOR_PROP ORANGE;
SET COLOR_DOT WHITE;
SET COLOR_ARC YELLOW;
SET COLOR_BODY GREEN;
SET COLOR_NOTE PURPLE;
SET PROP_DISPLAY VALUE;
SET PAGE_NUMBER P202;
FORCEADD QUANTA_TITLE_BLOCK_C..1
(0 0);
FORCEPROP 1 LAST CUSTOM_TXT_CDS <NAME_2>
J 0
(-3175 50);
FORCEPROP 1 LAST CUSTOM_TXT_CDS <NAME_1>
J 0
(-3175 175);
FORCEPROP 1 LAST CUSTOM_TXT_CDS <Q_NUMBER>
J 0
(-1403 103);
DISPLAY 1.212766 (-1403 103);
FORCEPROP 1 LAST CUSTOM_TXT_CDS <Q_PROJ>
J 0
(-2382 102);
DISPLAY 1.212766 (-2382 102);
FORCEPROP 1 LAST CUSTOM_TXT_CDS <Q_REV>
J 0
(-184 103);
DISPLAY 1.212766 (-184 103);
FORCEPROP 1 LAST CUSTOM_TXT_CDS <CON_LAST_MODIFIED>
J 0
(-1885 15);
DISPLAY 0.978723 (-1885 15);
FORCEPROP 1 LAST CUSTOM_TXT_CDS <CON_PAGE_NUM> OF <CON_TOTAL_PAGES>
J 0
(-446 18);
DISPLAY 0.978723 (-446 18);
FORCEPROP 1 LAST Q_TITLE Blank
J 0
(-9366 26);
DISPLAY 2.446809 (-9366 26);
PAINT GREEN (-9366 26);
FORCEPROP 1 LAST Q_DEPT BU9
J 1
(-3763 49);
DISPLAY 1.957447 (-3763 49);
PAINT GREEN (-3763 49);
FORCEPROP 0 LAST CDS_CON_LAST_MODIFIED Wed Jul 21 15:11:04 2021
J 0
(-1885 15);
DISPLAY INVISIBLE (-1885 15);
FORCEPROP 2 LAST PAGE_BORDER TRUE
J 0
(-7890 5250);
DISPLAY 0.638298 (-7890 5250);
PAINT PINK (-7890 5250);
DISPLAY INVISIBLE (-7890 5250);
FORCEPROP 1 LAST CDS_LMAN_SYM_OUTLINE -9475,6775,100,-125
J 0
(0 0);
DISPLAY 0.468085 (0 0);
PAINT GREEN (0 0);
DISPLAY INVISIBLE (0 0);
FORCEPROP 2 LAST CDS_LIB pure_quanta
J 0
(0 0);
DISPLAY INVISIBLE (0 0);
FORCEPROP 1 LAST COMMENT_BODY TRUE
J 0
(12 -13);
DISPLAY 0.978723 (12 -13);
PAINT GREEN (12 -13);
DISPLAY INVISIBLE (12 -13);
FORCEPROP 2 LAST CUSTOM_TXT_CDS <XR_PAGE_TITLE>
J 0
(-7890 5250);
DISPLAY 0.638298 (-7890 5250);
PAINT PINK (-7890 5250);
DISPLAY INVISIBLE (-7890 5250);
FORCEPROP 2 LAST CDS_XR_PAGE_TITLE CR-203 : @T6G_MB_LIB.T6G(SCH_1):PAGE203
J 0
(-7890 5250);
DISPLAY 0.638298 (-7890 5250);
PAINT PINK (-7890 5250);
DISPLAY INVISIBLE (-7890 5250);
QUIT
